# T6G (Grand Teton) — schematic netlist excerpt (pin names and nets, part order shuffled) for the footprints in the layout excerpt that follows; sources: Cadence DE-HDL packaged netlist, KiCad conversion of 04192023_DAF0TMB3IC0_F0TG_MB_C_brd_V02_OCP.brd

PU9  NCP3284AMNTXG  IC  pkg PQFN22_6X5  page 190
  ILIM  = P3V3_AUX_ILIM
  PGOOD  = PWRGD_P3V3_AUX_R1
  VIN  = P12V_AUX
  VCC  = P3V3_AUX_VCC
  VDRV  = P3V3_AUX_VDRV
  GL1  = NC_PU9_3
  PGND  = GND
  SW  = SW_P3V3_AUX_SW
  PVIN  = SW_P3V3_AUX_FLT
  PHASE  = SW_P3V3_AUX_BOOTR
  BOOT  = SW_P3V3_AUX_BOOT
  EN  = P3V3_AUX_EN
  VOS  = P3V3_AUX_VOS
  SS  = P3V3_AUX_SS
  FB  = P3V3_AUX_FB
  \vsns-\  = GND
  AGND  = GND
  NC1  = NC_PU9_1
  NC2  = NC_PU9_2
  \hiccup#\  = NC_HICCUP
  \mode||fset\  = P3V3_AUX_MODE
  GL2  = NC_PU9_4

(kicad_pcb
	(version 20260206)
	(generator "pcbnew")
	(generator_version "10.0")
	(general
		(thickness 1.6)
		(legacy_teardrops no)
	)
	(paper "A4")
	(title_block
		(title "04192023_DAF0TMB3IC0_F0TG_MB_C_brd_V02_OCP.brd")
		(comment 1 "Grand Teton / footprint 3043 of 8354 (PU9), pads 1-22 of 22")
	)
	(layers
		(0 "F.Cu" signal "TOP")
		(4 "In1.Cu" signal "GND")
		(6 "In2.Cu" signal "IN1")
		(8 "In3.Cu" signal "GND1")
		(10 "In4.Cu" signal "IN2")
		(12 "In5.Cu" signal "GND2")
		(14 "In6.Cu" signal "IN3")
		(16 "In7.Cu" signal "GND3")
		(18 "In8.Cu" signal "VCC")
		(20 "In9.Cu" signal "VCC1")
		(22 "In10.Cu" signal "GND4")
		(24 "In11.Cu" signal "IN4")
		(26 "In12.Cu" signal "GND5")
		(28 "In13.Cu" signal "IN5")
		(30 "In14.Cu" signal "GND6")
		(32 "In15.Cu" signal "IN6")
		(34 "In16.Cu" signal "GND7")
		(2 "B.Cu" signal "BOTTOM")
		(9 "F.Adhes" user "F.Adhesive")
		(11 "B.Adhes" user "B.Adhesive")
		(13 "F.Paste" user "Package Geometry/Pastemask Top")
		(15 "B.Paste" user "Package Geometry/Pastemask Bottom")
		(5 "F.SilkS" user "Ref Des/Silkscreen Top")
		(7 "B.SilkS" user "Ref Des/Silkscreen Bottom")
		(1 "F.Mask" user "Board Geometry/Soldermask Top")
		(3 "B.Mask" user "Board Geometry/Soldermask Bottom")
		(17 "Dwgs.User" user "User.Drawings")
		(19 "Cmts.User" user "User.Comments")
		(21 "Eco1.User" user "User.Eco1")
		(23 "Eco2.User" user "User.Eco2")
		(25 "Edge.Cuts" user "Board Geometry/Outline")
		(27 "Margin" user)
		(31 "F.CrtYd" user "Package Geometry/Place Bound Top")
		(29 "B.CrtYd" user "Package Geometry/Place Bound Bottom")
		(35 "F.Fab" user "Ref Des/Assembly Top")
		(33 "B.Fab" user "Ref Des/Assembly Bottom")
	)
	(footprint ""
		(layer "F.Cu")
		(at 456.50023 -51.066954 180)
		(property "Reference" "PU9"
			(at -4.50596 2.89306 0)
			(unlocked yes)
			(layer "F.SilkS")
			(effects
				(font
					(size 0.7874 0.5842)
					(thickness 0.1524)
				)
				(justify left)
			)
		)
		(property "Value" ""
			(at 0 0 180)
			(layer "F.Fab")
			(effects
				(font
					(size 1.27 1.27)
				)
			)
		)
		(duplicate_pad_numbers_are_jumpers no)
		(pad "1" smd rect
			(at -2.362708 -2.249932 270)
			(size 0.2794 0.5842)
			(layers "F.Cu" "F.Mask" "F.Paste")
			(net "P3V3_AUX_ILIM")
		)
		(pad "2" smd rect
			(at -2.350008 -1.75006 270)
			(size 0.2794 0.6096)
			(layers "F.Cu" "F.Mask" "F.Paste")
			(net "PWRGD_P3V3_AUX_R1")
		)
		(pad "3" smd rect
			(at -2.350008 -1.249934 270)
			(size 0.2794 0.6096)
			(layers "F.Cu" "F.Mask" "F.Paste")
			(net "P12V_AUX")
		)
		(pad "4" smd rect
			(at -2.350008 -0.750062 270)
			(size 0.2794 0.6096)
			(layers "F.Cu" "F.Mask" "F.Paste")
			(net "P3V3_AUX_VCC")
		)
		(pad "5" smd rect
			(at -2.350008 -0.249936 270)
			(size 0.2794 0.6096)
			(layers "F.Cu" "F.Mask" "F.Paste")
			(net "P3V3_AUX_VDRV")
		)
		(pad "6" smd rect
			(at -2.350008 0.249936 270)
			(size 0.2794 0.6096)
			(layers "F.Cu" "F.Mask" "F.Paste")
			(net "NC_PU9_3")
		)
		(pad "7_10-19" smd circle
			(at 0 0.062484 90)
			(size 0 0)
			(layers "F.Cu" "F.Mask" "F.Paste")
			(net "GND")
		)
		(pad "11_18" smd circle
			(at 0 2.712466 90)
			(size 0 0)
			(layers "F.Cu" "F.Mask" "F.Paste")
			(net "SW_P3V3_AUX_SW")
		)
		(pad "20_24" smd circle
			(at 1.787906 0.749808 180)
			(size 0 0)
			(layers "F.Cu" "F.Mask" "F.Paste")
			(net "SW_P3V3_AUX_FLT")
		)
		(pad "25" smd rect
			(at 2.350008 -0.750062 270)
			(size 0.2794 0.6096)
			(layers "F.Cu" "F.Mask" "F.Paste")
			(net "SW_P3V3_AUX_BOOTR")
		)
		(pad "26" smd rect
			(at 2.350008 -1.249934 270)
			(size 0.2794 0.6096)
			(layers "F.Cu" "F.Mask" "F.Paste")
			(net "SW_P3V3_AUX_BOOT")
		)
		(pad "27" smd rect
			(at 2.350008 -1.75006 270)
			(size 0.2794 0.6096)
			(layers "F.Cu" "F.Mask" "F.Paste")
			(net "P3V3_AUX_EN")
		)
		(pad "28" smd rect
			(at 2.362708 -2.249932 270)
			(size 0.2794 0.5842)
			(layers "F.Cu" "F.Mask" "F.Paste")
			(net "P3V3_AUX_VOS")
		)
		(pad "29" smd rect
			(at 1.75006 -2.887726 180)
			(size 0.2794 0.5842)
			(layers "F.Cu" "F.Mask" "F.Paste")
			(net "P3V3_AUX_SS")
		)
		(pad "30" smd rect
			(at 1.249934 -2.875026 180)
			(size 0.2794 0.6096)
			(layers "F.Cu" "F.Mask" "F.Paste")
			(net "P3V3_AUX_FB")
		)
		(pad "31" smd rect
			(at 0.750062 -2.875026 180)
			(size 0.2794 0.6096)
			(layers "F.Cu" "F.Mask" "F.Paste")
			(net "GND")
		)
		(pad "32" smd rect
			(at 0.249936 -2.875026 180)
			(size 0.2794 0.6096)
			(layers "F.Cu" "F.Mask" "F.Paste")
			(net "GND")
		)
		(pad "33" smd rect
			(at -0.249936 -2.875026 180)
			(size 0.2794 0.6096)
			(layers "F.Cu" "F.Mask" "F.Paste")
			(net "NC_PU9_1")
		)
		(pad "34" smd rect
			(at -0.750062 -2.875026 180)
			(size 0.2794 0.6096)
			(layers "F.Cu" "F.Mask" "F.Paste")
			(net "NC_PU9_2")
		)
		(pad "35" smd rect
			(at -1.249934 -2.875026 180)
			(size 0.2794 0.6096)
			(layers "F.Cu" "F.Mask" "F.Paste")
			(net "NC_HICCUP")
		)
		(pad "36" smd rect
			(at -1.75006 -2.887726 180)
			(size 0.2794 0.5842)
			(layers "F.Cu" "F.Mask" "F.Paste")
			(net "P3V3_AUX_MODE")
		)
		(pad "37" smd rect
			(at -1.549908 0.150114 270)
			(size 0.3048 0.508)
			(layers "F.Cu" "F.Mask" "F.Paste")
			(net "NC_PU9_4")
		)
	)
)
